# S9S_MB_2U (Grand Teton) — schematic netlist excerpt (pin names and nets, part order shuffled) for the footprints in the layout excerpt that follows; sources: Cadence DE-HDL packaged netlist, KiCad conversion of 03242023_DA0F0TMBIJ0_F0T_Motherboard_J_brd_V01_OCP.brd

R1820  Q_RES  10K 1% CHIP  pkg 0402LF  page 203 : A = P3V3_AUX ; B = FM_PLT_BMC_THERMTRIP_R_N
R4733  Q_RES  4.7K 5% CHIP  pkg 0402LF  page 144 : A = P3V3_AUX ; B = PRSNT_CABLE_SWB_B2_ISO_N

(kicad_pcb
	(version 20260206)
	(generator "pcbnew")
	(generator_version "10.0")
	(general
		(thickness 1.6)
		(legacy_teardrops no)
	)
	(paper "A4")
	(title_block
		(title "03242023_DA0F0TMBIJ0_F0T_Motherboard_J_brd_V01_OCP.brd")
		(comment 1 "Grand Teton / footprints 3385-3386 of 6105")
	)
	(layers
		(0 "F.Cu" signal "TOP")
		(4 "In1.Cu" signal "GND")
		(6 "In2.Cu" signal "IN1")
		(8 "In3.Cu" signal "GND1")
		(10 "In4.Cu" signal "IN2")
		(12 "In5.Cu" signal "GND2")
		(14 "In6.Cu" signal "IN3")
		(16 "In7.Cu" signal "GND3")
		(18 "In8.Cu" signal "VCC")
		(20 "In9.Cu" signal "VCC1")
		(22 "In10.Cu" signal "GND4")
		(24 "In11.Cu" signal "IN4")
		(26 "In12.Cu" signal "GND5")
		(28 "In13.Cu" signal "IN5")
		(30 "In14.Cu" signal "GND6")
		(32 "In15.Cu" signal "IN6")
		(34 "In16.Cu" signal "GND7")
		(2 "B.Cu" signal "BOTTOM")
		(9 "F.Adhes" user "F.Adhesive")
		(11 "B.Adhes" user "B.Adhesive")
		(13 "F.Paste" user "Package Geometry/Pastemask Top")
		(15 "B.Paste" user "Package Geometry/Pastemask Bottom")
		(5 "F.SilkS" user "Ref Des/Silkscreen Top")
		(7 "B.SilkS" user "Ref Des/Silkscreen Bottom")
		(1 "F.Mask" user "Board Geometry/Soldermask Top")
		(3 "B.Mask" user "Board Geometry/Soldermask Bottom")
		(17 "Dwgs.User" user "User.Drawings")
		(19 "Cmts.User" user "User.Comments")
		(21 "Eco1.User" user "User.Eco1")
		(23 "Eco2.User" user "User.Eco2")
		(25 "Edge.Cuts" user "Board Geometry/Outline")
		(27 "Margin" user)
		(31 "F.CrtYd" user "Package Geometry/Place Bound Top")
		(29 "B.CrtYd" user "Package Geometry/Place Bound Bottom")
		(35 "F.Fab" user "Ref Des/Assembly Top")
		(33 "B.Fab" user "Ref Des/Assembly Bottom")
	)
	(footprint ""
		(layer "F.Cu")
		(at 317.396622 -52.161948)
		(property "Reference" "R1820"
			(at 0 0 0)
			(layer "F.SilkS")
			(hide yes)
			(effects
				(font
					(size 1.27 1.27)
				)
			)
		)
		(property "Value" ""
			(at 0 0 0)
			(layer "F.Fab")
			(effects
				(font
					(size 1.27 1.27)
				)
			)
		)
		(duplicate_pad_numbers_are_jumpers no)
		(fp_line
			(start -0.7874 -0.4064)
			(end 0.7874 -0.4064)
			(stroke
				(width 0.1524)
				(type default)
			)
			(layer "F.SilkS")
		)
		(fp_line
			(start -0.7874 0.4064)
			(end -0.7874 -0.4064)
			(stroke
				(width 0.1524)
				(type default)
			)
			(layer "F.SilkS")
		)
		(fp_line
			(start 0.7874 -0.4064)
			(end 0.7874 0.4064)
			(stroke
				(width 0.1524)
				(type default)
			)
			(layer "F.SilkS")
		)
		(fp_line
			(start 0.7874 0.4064)
			(end -0.7874 0.4064)
			(stroke
				(width 0.1524)
				(type default)
			)
			(layer "F.SilkS")
		)
		(fp_line
			(start -0.67945 -0.305054)
			(end -0.12065 -0.305054)
			(stroke
				(width 0.1)
				(type default)
			)
			(layer "F.Fab")
		)
		(fp_line
			(start -0.67945 0.3048)
			(end -0.67945 -0.305054)
			(stroke
				(width 0.1)
				(type default)
			)
			(layer "F.Fab")
		)
		(fp_line
			(start -0.12065 -0.305054)
			(end -0.12065 -0.2794)
			(stroke
				(width 0.1)
				(type default)
			)
			(layer "F.Fab")
		)
		(fp_line
			(start -0.12065 -0.2794)
			(end 0.12065 -0.2794)
			(stroke
				(width 0.1)
				(type default)
			)
			(layer "F.Fab")
		)
		(fp_line
			(start -0.12065 0.2794)
			(end -0.12065 0.3048)
			(stroke
				(width 0.1)
				(type default)
			)
			(layer "F.Fab")
		)
		(fp_line
			(start -0.12065 0.3048)
			(end -0.67945 0.3048)
			(stroke
				(width 0.1)
				(type default)
			)
			(layer "F.Fab")
		)
		(fp_line
			(start 0.120396 0.2794)
			(end -0.12065 0.2794)
			(stroke
				(width 0.1)
				(type default)
			)
			(layer "F.Fab")
		)
		(fp_line
			(start 0.120396 0.3048)
			(end 0.120396 0.2794)
			(stroke
				(width 0.1)
				(type default)
			)
			(layer "F.Fab")
		)
		(fp_line
			(start 0.12065 -0.3048)
			(end 0.67945 -0.3048)
			(stroke
				(width 0.1)
				(type default)
			)
			(layer "F.Fab")
		)
		(fp_line
			(start 0.12065 -0.2794)
			(end 0.12065 -0.3048)
			(stroke
				(width 0.1)
				(type default)
			)
			(layer "F.Fab")
		)
		(fp_line
			(start 0.67945 -0.3048)
			(end 0.67945 0.3048)
			(stroke
				(width 0.1)
				(type default)
			)
			(layer "F.Fab")
		)
		(fp_line
			(start 0.67945 0.3048)
			(end 0.120396 0.3048)
			(stroke
				(width 0.1)
				(type default)
			)
			(layer "F.Fab")
		)
		(pad "1" smd circle
			(at -0.40005 0)
			(size 0 0)
			(layers "F.Cu" "F.Mask" "F.Paste")
			(net "P3V3_AUX")
		)
		(pad "2" smd circle
			(at 0.40005 0)
			(size 0 0)
			(layers "F.Cu" "F.Mask" "F.Paste")
			(net "FM_PLT_BMC_THERMTRIP_R_N")
		)
	)
	(footprint ""
		(layer "F.Cu")
		(at 355.8286 -402.9456)
		(property "Reference" "R4733"
			(at 0 0 0)
			(layer "F.SilkS")
			(hide yes)
			(effects
				(font
					(size 1.27 1.27)
				)
			)
		)
		(property "Value" ""
			(at 0 0 0)
			(layer "F.Fab")
			(effects
				(font
					(size 1.27 1.27)
				)
			)
		)
		(duplicate_pad_numbers_are_jumpers no)
		(fp_line
			(start -0.7874 -0.4064)
			(end 0.7874 -0.4064)
			(stroke
				(width 0.1524)
				(type default)
			)
			(layer "F.SilkS")
		)
		(fp_line
			(start -0.7874 0.4064)
			(end -0.7874 -0.4064)
			(stroke
				(width 0.1524)
				(type default)
			)
			(layer "F.SilkS")
		)
		(fp_line
			(start 0.7874 -0.4064)
			(end 0.7874 0.4064)
			(stroke
				(width 0.1524)
				(type default)
			)
			(layer "F.SilkS")
		)
		(fp_line
			(start 0.7874 0.4064)
			(end -0.7874 0.4064)
			(stroke
				(width 0.1524)
				(type default)
			)
			(layer "F.SilkS")
		)
		(fp_line
			(start -0.67945 -0.305054)
			(end -0.12065 -0.305054)
			(stroke
				(width 0.1)
				(type default)
			)
			(layer "F.Fab")
		)
		(fp_line
			(start -0.67945 0.3048)
			(end -0.67945 -0.305054)
			(stroke
				(width 0.1)
				(type default)
			)
			(layer "F.Fab")
		)
		(fp_line
			(start -0.12065 -0.305054)
			(end -0.12065 -0.2794)
			(stroke
				(width 0.1)
				(type default)
			)
			(layer "F.Fab")
		)
		(fp_line
			(start -0.12065 -0.2794)
			(end 0.12065 -0.2794)
			(stroke
				(width 0.1)
				(type default)
			)
			(layer "F.Fab")
		)
		(fp_line
			(start -0.12065 0.2794)
			(end -0.12065 0.3048)
			(stroke
				(width 0.1)
				(type default)
			)
			(layer "F.Fab")
		)
		(fp_line
			(start -0.12065 0.3048)
			(end -0.67945 0.3048)
			(stroke
				(width 0.1)
				(type default)
			)
			(layer "F.Fab")
		)
		(fp_line
			(start 0.120396 0.2794)
			(end -0.12065 0.2794)
			(stroke
				(width 0.1)
				(type default)
			)
			(layer "F.Fab")
		)
		(fp_line
			(start 0.120396 0.3048)
			(end 0.120396 0.2794)
			(stroke
				(width 0.1)
				(type default)
			)
			(layer "F.Fab")
		)
		(fp_line
			(start 0.12065 -0.3048)
			(end 0.67945 -0.3048)
			(stroke
				(width 0.1)
				(type default)
			)
			(layer "F.Fab")
		)
		(fp_line
			(start 0.12065 -0.2794)
			(end 0.12065 -0.3048)
			(stroke
				(width 0.1)
				(type default)
			)
			(layer "F.Fab")
		)
		(fp_line
			(start 0.67945 -0.3048)
			(end 0.67945 0.3048)
			(stroke
				(width 0.1)
				(type default)
			)
			(layer "F.Fab")
		)
		(fp_line
			(start 0.67945 0.3048)
			(end 0.120396 0.3048)
			(stroke
				(width 0.1)
				(type default)
			)
			(layer "F.Fab")
		)
		(pad "1" smd circle
			(at -0.40005 0)
			(size 0 0)
			(layers "F.Cu" "F.Mask" "F.Paste")
			(net "P3V3_AUX")
		)
		(pad "2" smd circle
			(at 0.40005 0)
			(size 0 0)
			(layers "F.Cu" "F.Mask" "F.Paste")
			(net "PRSNT_CABLE_SWB_B2_ISO_N")
		)
	)
)
